(kicad_pcb
	(version 20260206)
	(generator "pcbnew")
	(generator_version "10.0")
	(general
		(thickness 1.6)
		(legacy_teardrops no)
	)
	(paper "A4")
	(title_block
		(title "Bryce Canyon_SCC_16316-1_OCP.brd")
		(comment 1 "Bryce Canyon / footprints 169-176 of 1561")
	)
	(layers
		(0 "F.Cu" signal "TOP")
		(4 "In1.Cu" signal "L2GND")
		(6 "In2.Cu" signal "L3")
		(8 "In3.Cu" signal "L4VCC")
		(10 "In4.Cu" signal "L5VCC")
		(12 "In5.Cu" signal "L6")
		(14 "In6.Cu" signal "L7GND")
		(2 "B.Cu" signal "BOTTOM")
		(9 "F.Adhes" user "F.Adhesive")
		(11 "B.Adhes" user "B.Adhesive")
		(13 "F.Paste" user "Package Geometry/Pastemask Top")
		(15 "B.Paste" user "Package Geometry/Pastemask Bottom")
		(5 "F.SilkS" user "Ref Des/Silkscreen Top")
		(7 "B.SilkS" user "Ref Des/Silkscreen Bottom")
		(1 "F.Mask" user "Board Geometry/Soldermask Top")
		(3 "B.Mask" user "Board Geometry/Soldermask Bottom")
		(17 "Dwgs.User" user "User.Drawings")
		(19 "Cmts.User" user "User.Comments")
		(21 "Eco1.User" user "User.Eco1")
		(23 "Eco2.User" user "User.Eco2")
		(25 "Edge.Cuts" user "Board Geometry/Outline")
		(27 "Margin" user)
		(31 "F.CrtYd" user "Package Geometry/Place Bound Top")
		(29 "B.CrtYd" user "Package Geometry/Place Bound Bottom")
		(35 "F.Fab" user "Ref Des/Assembly Top")
		(33 "B.Fab" user "Ref Des/Assembly Bottom")
	)
	(footprint ""
		(layer "F.Cu")
		(at 89.789 -66.675)
		(property "Reference" "TP165"
			(at 0 0 0)
			(layer "F.SilkS")
			(hide yes)
			(effects
				(font
					(size 1.27 1.27)
				)
			)
		)
		(property "Value" "TPAD28-2-GP"
			(at -0.0127 -1.6637 0)
			(unlocked yes)
			(layer "F.Fab")
			(hide yes)
			(effects
				(font
					(size 1.016 1.016)
					(thickness 0.1524)
				)
			)
		)
		(property "Device Type" "TPAD28"
			(at -0.0127 -3.1877 0)
			(unlocked yes)
			(layer "F.Fab")
			(hide yes)
			(effects
				(font
					(size 1.016 1.016)
					(thickness 0.1524)
				)
			)
		)
		(duplicate_pad_numbers_are_jumpers no)
		(fp_poly
			(pts
				(arc
					(start 0.3556 0)
					(mid -0.3556 0)
					(end 0.3556 0)
				)
			)
			(stroke
				(width 0)
				(type default)
			)
			(fill no)
			(layer "F.CrtYd")
		)
		(fp_poly
			(pts
				(arc
					(start 0.6096 0)
					(mid -0.6096 0)
					(end 0.6096 0)
				)
			)
			(stroke
				(width 0)
				(type default)
			)
			(fill no)
			(layer "F.Fab")
		)
		(pad "1" smd circle
			(at 0 0)
			(size 0.7112 0.7112)
			(layers "F.Cu" "F.Mask" "F.Paste")
			(net "LED46")
		)
	)
	(footprint ""
		(layer "F.Cu")
		(at 172.339 -57.785)
		(property "Reference" "TP142"
			(at 0 0 0)
			(layer "F.SilkS")
			(hide yes)
			(effects
				(font
					(size 1.27 1.27)
				)
			)
		)
		(property "Value" "TPAD28-2-GP"
			(at -0.0127 -1.6637 0)
			(unlocked yes)
			(layer "F.Fab")
			(hide yes)
			(effects
				(font
					(size 1.016 1.016)
					(thickness 0.1524)
				)
			)
		)
		(property "Device Type" "TPAD28"
			(at -0.0127 -3.1877 0)
			(unlocked yes)
			(layer "F.Fab")
			(hide yes)
			(effects
				(font
					(size 1.016 1.016)
					(thickness 0.1524)
				)
			)
		)
		(duplicate_pad_numbers_are_jumpers no)
		(fp_poly
			(pts
				(arc
					(start 0.3556 0)
					(mid -0.3556 0)
					(end 0.3556 0)
				)
			)
			(stroke
				(width 0)
				(type default)
			)
			(fill no)
			(layer "F.CrtYd")
		)
		(fp_poly
			(pts
				(arc
					(start 0.6096 0)
					(mid -0.6096 0)
					(end 0.6096 0)
				)
			)
			(stroke
				(width 0)
				(type default)
			)
			(fill no)
			(layer "F.Fab")
		)
		(pad "1" smd circle
			(at 0 0)
			(size 0.7112 0.7112)
			(layers "F.Cu" "F.Mask" "F.Paste")
			(net "LSI_TN")
		)
	)
	(footprint ""
		(layer "F.Cu")
		(at 64.00165 -80.509618 90)
		(property "Reference" "C550"
			(at 0 0 90)
			(layer "F.SilkS")
			(hide yes)
			(effects
				(font
					(size 1.27 1.27)
				)
			)
		)
		(property "Value" "SCD1U16V2KX-3GP"
			(at 1.1811 -2.7051 90)
			(unlocked yes)
			(layer "F.Fab")
			(hide yes)
			(effects
				(font
					(size 1.016 1.016)
					(thickness 0.1524)
				)
			)
		)
		(property "Device Type" "C402H22"
			(at 1.1811 -4.2291 90)
			(unlocked yes)
			(layer "F.Fab")
			(hide yes)
			(effects
				(font
					(size 1.016 1.016)
					(thickness 0.1524)
				)
			)
		)
		(duplicate_pad_numbers_are_jumpers no)
		(fp_rect
			(start -0.4318 0.9525)
			(end 0.4318 -0.9525)
			(stroke
				(width 0)
				(type default)
			)
			(fill no)
			(layer "F.CrtYd")
		)
		(fp_rect
			(start -0.4318 0.9525)
			(end 0.4318 -0.9525)
			(stroke
				(width 0)
				(type default)
			)
			(fill no)
			(layer "F.Fab")
		)
		(pad "1" smd custom
			(at 0 -0.4445 90)
			(size 0.1524 0.1524)
			(layers "F.Cu" "F.Mask" "F.Paste")
			(net "P1V8_E")
			(options
				(clearance outline)
				(anchor circle)
			)
			(primitives
				(gr_poly
					(pts
						(arc
							(start 0.3048 -0.2032)
							(mid 0.275042 -0.275042)
							(end 0.2032 -0.3048)
						)
						(arc
							(start -0.2032 -0.3048)
							(mid -0.275042 -0.275042)
							(end -0.3048 -0.2032)
						)
						(arc
							(start -0.3048 0.2032)
							(mid -0.275042 0.275042)
							(end -0.2032 0.3048)
						)
						(arc
							(start 0.2032 0.3048)
							(mid 0.275042 0.275042)
							(end 0.3048 0.2032)
						)
					)
					(width 0)
					(fill yes)
				)
			)
		)
		(pad "2" smd custom
			(at 0 0.4445 90)
			(size 0.1524 0.1524)
			(layers "F.Cu" "F.Mask" "F.Paste")
			(net "GND")
			(options
				(clearance outline)
				(anchor circle)
			)
			(primitives
				(gr_poly
					(pts
						(arc
							(start 0.3048 -0.2032)
							(mid 0.275042 -0.275042)
							(end 0.2032 -0.3048)
						)
						(arc
							(start -0.2032 -0.3048)
							(mid -0.275042 -0.275042)
							(end -0.3048 -0.2032)
						)
						(arc
							(start -0.3048 0.2032)
							(mid -0.275042 0.275042)
							(end -0.2032 0.3048)
						)
						(arc
							(start 0.2032 0.3048)
							(mid 0.275042 0.275042)
							(end 0.3048 0.2032)
						)
					)
					(width 0)
					(fill yes)
				)
			)
		)
	)
	(footprint ""
		(layer "F.Cu")
		(at 22.7584 -99.7966 180)
		(property "Reference" "R533"
			(at 0 0 180)
			(layer "F.SilkS")
			(hide yes)
			(effects
				(font
					(size 1.27 1.27)
				)
			)
		)
		(property "Value" "0R2J-2-GP"
			(at 0.064008 -3.993896 180)
			(unlocked yes)
			(layer "F.Fab")
			(hide yes)
			(effects
				(font
					(size 1.016 1.016)
					(thickness 0.1524)
				)
			)
		)
		(property "Device Type" "R402H16"
			(at 0.064008 -5.517896 180)
			(unlocked yes)
			(layer "F.Fab")
			(hide yes)
			(effects
				(font
					(size 1.016 1.016)
					(thickness 0.1524)
				)
			)
		)
		(duplicate_pad_numbers_are_jumpers no)
		(fp_line
			(start 0.508 -0.9398)
			(end -0.508 -0.9398)
			(stroke
				(width 0.1524)
				(type default)
			)
			(layer "F.SilkS")
		)
		(fp_line
			(start -0.508 -0.9398)
			(end -0.508 0.9398)
			(stroke
				(width 0.1524)
				(type default)
			)
			(layer "F.SilkS")
		)
		(fp_rect
			(start -0.508 0.9398)
			(end 0.508 -0.9398)
			(stroke
				(width 0)
				(type default)
			)
			(fill no)
			(layer "F.CrtYd")
		)
		(fp_rect
			(start -0.508 0.9398)
			(end 0.508 -0.9398)
			(stroke
				(width 0)
				(type default)
			)
			(fill no)
			(layer "F.Fab")
		)
		(pad "1" smd custom
			(at 0 -0.4445 180)
			(size 0.1397 0.1397)
			(layers "F.Cu" "F.Mask" "F.Paste")
			(net "SCC_STBY_PGOOD_BUF")
			(options
				(clearance outline)
				(anchor circle)
			)
			(primitives
				(gr_poly
					(pts
						(arc
							(start -0.1778 -0.2794)
							(mid -0.249642 -0.249642)
							(end -0.2794 -0.1778)
						)
						(arc
							(start -0.2794 0.1778)
							(mid -0.249642 0.249642)
							(end -0.1778 0.2794)
						)
						(arc
							(start 0.1778 0.2794)
							(mid 0.249642 0.249642)
							(end 0.2794 0.1778)
						)
						(arc
							(start 0.2794 -0.1778)
							(mid 0.249642 -0.249642)
							(end 0.1778 -0.2794)
						)
					)
					(width 0)
					(fill yes)
				)
			)
		)
		(pad "2" smd custom
			(at 0 0.4445 180)
			(size 0.1397 0.1397)
			(layers "F.Cu" "F.Mask" "F.Paste")
			(net "SCC_STBY_PGOOD_R")
			(options
				(clearance outline)
				(anchor circle)
			)
			(primitives
				(gr_poly
					(pts
						(arc
							(start -0.1778 -0.2794)
							(mid -0.249642 -0.249642)
							(end -0.2794 -0.1778)
						)
						(arc
							(start -0.2794 0.1778)
							(mid -0.249642 0.249642)
							(end -0.1778 0.2794)
						)
						(arc
							(start 0.1778 0.2794)
							(mid 0.249642 0.249642)
							(end 0.2794 0.1778)
						)
						(arc
							(start 0.2794 -0.1778)
							(mid 0.249642 -0.249642)
							(end 0.1778 -0.2794)
						)
					)
					(width 0)
					(fill yes)
				)
			)
		)
	)
	(footprint ""
		(layer "F.Cu")
		(at 126.4666 -87.2744 180)
		(property "Reference" "R103"
			(at 0 0 180)
			(layer "F.SilkS")
			(hide yes)
			(effects
				(font
					(size 1.27 1.27)
				)
			)
		)
		(property "Value" "0R2J-2-GP"
			(at 0.064008 -3.993896 180)
			(unlocked yes)
			(layer "F.Fab")
			(hide yes)
			(effects
				(font
					(size 1.016 1.016)
					(thickness 0.1524)
				)
			)
		)
		(property "Device Type" "R402H16"
			(at 0.064008 -5.517896 180)
			(unlocked yes)
			(layer "F.Fab")
			(hide yes)
			(effects
				(font
					(size 1.016 1.016)
					(thickness 0.1524)
				)
			)
		)
		(duplicate_pad_numbers_are_jumpers no)
		(fp_line
			(start 0.508 -0.9398)
			(end -0.508 -0.9398)
			(stroke
				(width 0.1524)
				(type default)
			)
			(layer "F.SilkS")
		)
		(fp_line
			(start -0.508 -0.9398)
			(end -0.508 0.9398)
			(stroke
				(width 0.1524)
				(type default)
			)
			(layer "F.SilkS")
		)
		(fp_rect
			(start -0.508 0.9398)
			(end 0.508 -0.9398)
			(stroke
				(width 0)
				(type default)
			)
			(fill no)
			(layer "F.CrtYd")
		)
		(fp_rect
			(start -0.508 0.9398)
			(end 0.508 -0.9398)
			(stroke
				(width 0)
				(type default)
			)
			(fill no)
			(layer "F.Fab")
		)
		(pad "1" smd custom
			(at 0 -0.4445 180)
			(size 0.1397 0.1397)
			(layers "F.Cu" "F.Mask" "F.Paste")
			(net "SDB_R_RX")
			(options
				(clearance outline)
				(anchor circle)
			)
			(primitives
				(gr_poly
					(pts
						(arc
							(start -0.1778 -0.2794)
							(mid -0.249642 -0.249642)
							(end -0.2794 -0.1778)
						)
						(arc
							(start -0.2794 0.1778)
							(mid -0.249642 0.249642)
							(end -0.1778 0.2794)
						)
						(arc
							(start 0.1778 0.2794)
							(mid 0.249642 0.249642)
							(end 0.2794 0.1778)
						)
						(arc
							(start 0.2794 -0.1778)
							(mid 0.249642 -0.249642)
							(end 0.1778 -0.2794)
						)
					)
					(width 0)
					(fill yes)
				)
			)
		)
		(pad "2" smd custom
			(at 0 0.4445 180)
			(size 0.1397 0.1397)
			(layers "F.Cu" "F.Mask" "F.Paste")
			(net "SDB_RX")
			(options
				(clearance outline)
				(anchor circle)
			)
			(primitives
				(gr_poly
					(pts
						(arc
							(start -0.1778 -0.2794)
							(mid -0.249642 -0.249642)
							(end -0.2794 -0.1778)
						)
						(arc
							(start -0.2794 0.1778)
							(mid -0.249642 0.249642)
							(end -0.1778 0.2794)
						)
						(arc
							(start 0.1778 0.2794)
							(mid 0.249642 0.249642)
							(end 0.2794 0.1778)
						)
						(arc
							(start 0.2794 -0.1778)
							(mid 0.249642 -0.249642)
							(end 0.1778 -0.2794)
						)
					)
					(width 0)
					(fill yes)
				)
			)
		)
	)
	(footprint ""
		(layer "F.Cu")
		(at 185.3946 -120.7516 -90)
		(property "Reference" "R9"
			(at 0 0 270)
			(layer "F.SilkS")
			(hide yes)
			(effects
				(font
					(size 1.27 1.27)
				)
			)
		)
		(property "Value" "1KR2F-3-GP"
			(at 0.064008 -3.993896 270)
			(unlocked yes)
			(layer "F.Fab")
			(hide yes)
			(effects
				(font
					(size 1.016 1.016)
					(thickness 0.1524)
				)
			)
		)
		(property "Device Type" "R402H16"
			(at 0.064008 -5.517896 270)
			(unlocked yes)
			(layer "F.Fab")
			(hide yes)
			(effects
				(font
					(size 1.016 1.016)
					(thickness 0.1524)
				)
			)
		)
		(duplicate_pad_numbers_are_jumpers no)
		(fp_line
			(start -0.508 -0.9398)
			(end -0.508 0.9398)
			(stroke
				(width 0.1524)
				(type default)
			)
			(layer "F.SilkS")
		)
		(fp_line
			(start 0.508 -0.9398)
			(end -0.508 -0.9398)
			(stroke
				(width 0.1524)
				(type default)
			)
			(layer "F.SilkS")
		)
		(fp_rect
			(start -0.508 0.9398)
			(end 0.508 -0.9398)
			(stroke
				(width 0)
				(type default)
			)
			(fill no)
			(layer "F.CrtYd")
		)
		(fp_rect
			(start -0.508 0.9398)
			(end 0.508 -0.9398)
			(stroke
				(width 0)
				(type default)
			)
			(fill no)
			(layer "F.Fab")
		)
		(pad "1" smd custom
			(at 0 -0.4445 270)
			(size 0.1397 0.1397)
			(layers "F.Cu" "F.Mask" "F.Paste")
			(net "P1V8_C")
			(options
				(clearance outline)
				(anchor circle)
			)
			(primitives
				(gr_poly
					(pts
						(arc
							(start -0.1778 -0.2794)
							(mid -0.249642 -0.249642)
							(end -0.2794 -0.1778)
						)
						(arc
							(start -0.2794 0.1778)
							(mid -0.249642 0.249642)
							(end -0.1778 0.2794)
						)
						(arc
							(start 0.1778 0.2794)
							(mid 0.249642 0.249642)
							(end 0.2794 0.1778)
						)
						(arc
							(start 0.2794 -0.1778)
							(mid 0.249642 -0.249642)
							(end 0.1778 -0.2794)
						)
					)
					(width 0)
					(fill yes)
				)
			)
		)
		(pad "2" smd custom
			(at 0 0.4445 270)
			(size 0.1397 0.1397)
			(layers "F.Cu" "F.Mask" "F.Paste")
			(net "GND")
			(options
				(clearance outline)
				(anchor circle)
			)
			(primitives
				(gr_poly
					(pts
						(arc
							(start -0.1778 -0.2794)
							(mid -0.249642 -0.249642)
							(end -0.2794 -0.1778)
						)
						(arc
							(start -0.2794 0.1778)
							(mid -0.249642 0.249642)
							(end -0.1778 0.2794)
						)
						(arc
							(start 0.1778 0.2794)
							(mid 0.249642 0.249642)
							(end 0.2794 0.1778)
						)
						(arc
							(start 0.2794 -0.1778)
							(mid 0.249642 -0.249642)
							(end 0.1778 -0.2794)
						)
					)
					(width 0)
					(fill yes)
				)
			)
		)
	)
	(footprint ""
		(layer "F.Cu")
		(at 72.952356 -73.638918)
		(property "Reference" "R542"
			(at 0 0 0)
			(layer "F.SilkS")
			(hide yes)
			(effects
				(font
					(size 1.27 1.27)
				)
			)
		)
		(property "Value" "0R2J-2-GP"
			(at 0.064008 -3.993896 0)
			(unlocked yes)
			(layer "F.Fab")
			(hide yes)
			(effects
				(font
					(size 1.016 1.016)
					(thickness 0.1524)
				)
			)
		)
		(property "Device Type" "R402H16"
			(at 0.064008 -5.517896 0)
			(unlocked yes)
			(layer "F.Fab")
			(hide yes)
			(effects
				(font
					(size 1.016 1.016)
					(thickness 0.1524)
				)
			)
		)
		(duplicate_pad_numbers_are_jumpers no)
		(fp_line
			(start -0.508 -0.9398)
			(end -0.508 0.9398)
			(stroke
				(width 0.1524)
				(type default)
			)
			(layer "F.SilkS")
		)
		(fp_line
			(start 0.508 -0.9398)
			(end -0.508 -0.9398)
			(stroke
				(width 0.1524)
				(type default)
			)
			(layer "F.SilkS")
		)
		(fp_rect
			(start -0.508 0.9398)
			(end 0.508 -0.9398)
			(stroke
				(width 0)
				(type default)
			)
			(fill no)
			(layer "F.CrtYd")
		)
		(fp_rect
			(start -0.508 0.9398)
			(end 0.508 -0.9398)
			(stroke
				(width 0)
				(type default)
			)
			(fill no)
			(layer "F.Fab")
		)
		(pad "1" smd custom
			(at 0 -0.4445)
			(size 0.1397 0.1397)
			(layers "F.Cu" "F.Mask" "F.Paste")
			(net "I2C_IOC_4_R_SDA")
			(options
				(clearance outline)
				(anchor circle)
			)
			(primitives
				(gr_poly
					(pts
						(arc
							(start -0.1778 -0.2794)
							(mid -0.249642 -0.249642)
							(end -0.2794 -0.1778)
						)
						(arc
							(start -0.2794 0.1778)
							(mid -0.249642 0.249642)
							(end -0.1778 0.2794)
						)
						(arc
							(start 0.1778 0.2794)
							(mid 0.249642 0.249642)
							(end 0.2794 0.1778)
						)
						(arc
							(start 0.2794 -0.1778)
							(mid 0.249642 -0.249642)
							(end 0.1778 -0.2794)
						)
					)
					(width 0)
					(fill yes)
				)
			)
		)
		(pad "2" smd custom
			(at 0 0.4445)
			(size 0.1397 0.1397)
			(layers "F.Cu" "F.Mask" "F.Paste")
			(net "I2C_IOC_4_SDA")
			(options
				(clearance outline)
				(anchor circle)
			)
			(primitives
				(gr_poly
					(pts
						(arc
							(start -0.1778 -0.2794)
							(mid -0.249642 -0.249642)
							(end -0.2794 -0.1778)
						)
						(arc
							(start -0.2794 0.1778)
							(mid -0.249642 0.249642)
							(end -0.1778 0.2794)
						)
						(arc
							(start 0.1778 0.2794)
							(mid 0.249642 0.249642)
							(end 0.2794 0.1778)
						)
						(arc
							(start 0.2794 -0.1778)
							(mid 0.249642 -0.249642)
							(end 0.1778 -0.2794)
						)
					)
					(width 0)
					(fill yes)
				)
			)
		)
	)
	(footprint ""
		(layer "F.Cu")
		(at 157.166818 -95.223076 -90)
		(property "Reference" "R314"
			(at 0 0 270)
			(layer "F.SilkS")
			(hide yes)
			(effects
				(font
					(size 1.27 1.27)
				)
			)
		)
		(property "Value" "0R2J-2-GP"
			(at 0.064008 -3.993896 270)
			(unlocked yes)
			(layer "F.Fab")
			(hide yes)
			(effects
				(font
					(size 1.016 1.016)
					(thickness 0.1524)
				)
			)
		)
		(property "Device Type" "R402H16"
			(at 0.064008 -5.517896 270)
			(unlocked yes)
			(layer "F.Fab")
			(hide yes)
			(effects
				(font
					(size 1.016 1.016)
					(thickness 0.1524)
				)
			)
		)
		(duplicate_pad_numbers_are_jumpers no)
		(fp_line
			(start -0.508 -0.9398)
			(end -0.508 0.9398)
			(stroke
				(width 0.1524)
				(type default)
			)
			(layer "F.SilkS")
		)
		(fp_line
			(start 0.508 -0.9398)
			(end -0.508 -0.9398)
			(stroke
				(width 0.1524)
				(type default)
			)
			(layer "F.SilkS")
		)
		(fp_rect
			(start -0.508 0.9398)
			(end 0.508 -0.9398)
			(stroke
				(width 0)
				(type default)
			)
			(fill no)
			(layer "F.CrtYd")
		)
		(fp_rect
			(start -0.508 0.9398)
			(end 0.508 -0.9398)
			(stroke
				(width 0)
				(type default)
			)
			(fill no)
			(layer "F.Fab")
		)
		(pad "1" smd custom
			(at 0 -0.4445 270)
			(size 0.1397 0.1397)
			(layers "F.Cu" "F.Mask" "F.Paste")
			(net "UART_EXP_TX")
			(options
				(clearance outline)
				(anchor circle)
			)
			(primitives
				(gr_poly
					(pts
						(arc
							(start -0.1778 -0.2794)
							(mid -0.249642 -0.249642)
							(end -0.2794 -0.1778)
						)
						(arc
							(start -0.2794 0.1778)
							(mid -0.249642 0.249642)
							(end -0.1778 0.2794)
						)
						(arc
							(start 0.1778 0.2794)
							(mid 0.249642 0.249642)
							(end 0.2794 0.1778)
						)
						(arc
							(start 0.2794 -0.1778)
							(mid 0.249642 -0.249642)
							(end 0.1778 -0.2794)
						)
					)
					(width 0)
					(fill yes)
				)
			)
		)
		(pad "2" smd custom
			(at 0 0.4445 270)
			(size 0.1397 0.1397)
			(layers "F.Cu" "F.Mask" "F.Paste")
			(net "EXP_SMART_TX_R")
			(options
				(clearance outline)
				(anchor circle)
			)
			(primitives
				(gr_poly
					(pts
						(arc
							(start -0.1778 -0.2794)
							(mid -0.249642 -0.249642)
							(end -0.2794 -0.1778)
						)
						(arc
							(start -0.2794 0.1778)
							(mid -0.249642 0.249642)
							(end -0.1778 0.2794)
						)
						(arc
							(start 0.1778 0.2794)
							(mid 0.249642 0.249642)
							(end 0.2794 0.1778)
						)
						(arc
							(start 0.2794 -0.1778)
							(mid 0.249642 -0.249642)
							(end 0.1778 -0.2794)
						)
					)
					(width 0)
					(fill yes)
				)
			)
		)
	)
)
